FILE_TYPE=LIBRARY_PARTS;
TIME=' Created/Modified on Fri Apr 03 13:04:35 2009' ;
primitive '74LVC1G32GW';
  pin
    'I0':
      PIN_NUMBER='(1)';
      INPUT_LOAD='(-0.01,0.01)';
    'I1':
      PIN_NUMBER='(2)';
      INPUT_LOAD='(-0.01,0.01)';
    'O':
      PIN_NUMBER='(4)';
      OUTPUT_LOAD='(1.0,-1.0)';
    'VCC':
      PIN_NUMBER='(5)';
      PINUSE='POWER';
    'GND':
      PIN_NUMBER='(3)';
      PINUSE='POWER';
  end_pin;
  body
    CLASS='IC';
    PART_NAME='74LVC1G32GW';
    PHYS_DES_PREFIX='U';
  end_body;
end_primitive;
END.
